(kicad_pcb
	(version 20260206)
	(generator "pcbnew")
	(generator_version "10.0")
	(general
		(thickness 1.6)
		(legacy_teardrops no)
	)
	(paper "A4")
	(title_block
		(title "04192023_DAF0TMB3IC0_F0TG_MB_C_brd_V02_OCP.brd")
		(comment 1 "Grand Teton / footprints 2166-2169 of 8354")
	)
	(layers
		(0 "F.Cu" signal "TOP")
		(4 "In1.Cu" signal "GND")
		(6 "In2.Cu" signal "IN1")
		(8 "In3.Cu" signal "GND1")
		(10 "In4.Cu" signal "IN2")
		(12 "In5.Cu" signal "GND2")
		(14 "In6.Cu" signal "IN3")
		(16 "In7.Cu" signal "GND3")
		(18 "In8.Cu" signal "VCC")
		(20 "In9.Cu" signal "VCC1")
		(22 "In10.Cu" signal "GND4")
		(24 "In11.Cu" signal "IN4")
		(26 "In12.Cu" signal "GND5")
		(28 "In13.Cu" signal "IN5")
		(30 "In14.Cu" signal "GND6")
		(32 "In15.Cu" signal "IN6")
		(34 "In16.Cu" signal "GND7")
		(2 "B.Cu" signal "BOTTOM")
		(9 "F.Adhes" user "F.Adhesive")
		(11 "B.Adhes" user "B.Adhesive")
		(13 "F.Paste" user "Package Geometry/Pastemask Top")
		(15 "B.Paste" user "Package Geometry/Pastemask Bottom")
		(5 "F.SilkS" user "Ref Des/Silkscreen Top")
		(7 "B.SilkS" user "Ref Des/Silkscreen Bottom")
		(1 "F.Mask" user "Board Geometry/Soldermask Top")
		(3 "B.Mask" user "Board Geometry/Soldermask Bottom")
		(17 "Dwgs.User" user "User.Drawings")
		(19 "Cmts.User" user "User.Comments")
		(21 "Eco1.User" user "User.Eco1")
		(23 "Eco2.User" user "User.Eco2")
		(25 "Edge.Cuts" user "Board Geometry/Outline")
		(27 "Margin" user)
		(31 "F.CrtYd" user "Package Geometry/Place Bound Top")
		(29 "B.CrtYd" user "Package Geometry/Place Bound Bottom")
		(35 "F.Fab" user "Ref Des/Assembly Top")
		(33 "B.Fab" user "Ref Des/Assembly Bottom")
	)
	(footprint ""
		(layer "F.Cu")
		(at 351.410778 -158.474156 -90)
		(property "Reference" "PC151"
			(at 0 0 270)
			(layer "F.SilkS")
			(hide yes)
			(effects
				(font
					(size 1.27 1.27)
				)
			)
		)
		(property "Value" ""
			(at 0 0 270)
			(layer "F.Fab")
			(effects
				(font
					(size 1.27 1.27)
				)
			)
		)
		(duplicate_pad_numbers_are_jumpers no)
		(fp_line
			(start -0.7874 0.4064)
			(end -0.7874 -0.4064)
			(stroke
				(width 0.1524)
				(type default)
			)
			(layer "F.SilkS")
		)
		(fp_line
			(start -0.174244 0.4064)
			(end -0.7874 0.4064)
			(stroke
				(width 0.1524)
				(type default)
			)
			(layer "F.SilkS")
		)
		(fp_line
			(start 0.7874 0.4064)
			(end 0.359156 0.4064)
			(stroke
				(width 0.1524)
				(type default)
			)
			(layer "F.SilkS")
		)
		(fp_line
			(start -0.7874 -0.4064)
			(end 0.7874 -0.4064)
			(stroke
				(width 0.1524)
				(type default)
			)
			(layer "F.SilkS")
		)
		(fp_line
			(start 0.7874 -0.4064)
			(end 0.7874 0.4064)
			(stroke
				(width 0.1524)
				(type default)
			)
			(layer "F.SilkS")
		)
		(fp_line
			(start -0.67945 0.3048)
			(end -0.67945 -0.305054)
			(stroke
				(width 0.1)
				(type default)
			)
			(layer "F.Fab")
		)
		(fp_line
			(start -0.12065 0.3048)
			(end -0.67945 0.3048)
			(stroke
				(width 0.1)
				(type default)
			)
			(layer "F.Fab")
		)
		(fp_line
			(start 0.120396 0.3048)
			(end 0.120396 0.2794)
			(stroke
				(width 0.1)
				(type default)
			)
			(layer "F.Fab")
		)
		(fp_line
			(start 0.67945 0.3048)
			(end 0.120396 0.3048)
			(stroke
				(width 0.1)
				(type default)
			)
			(layer "F.Fab")
		)
		(fp_line
			(start -0.12065 0.2794)
			(end -0.12065 0.3048)
			(stroke
				(width 0.1)
				(type default)
			)
			(layer "F.Fab")
		)
		(fp_line
			(start 0.120396 0.2794)
			(end -0.12065 0.2794)
			(stroke
				(width 0.1)
				(type default)
			)
			(layer "F.Fab")
		)
		(fp_line
			(start -0.12065 -0.2794)
			(end 0.12065 -0.2794)
			(stroke
				(width 0.1)
				(type default)
			)
			(layer "F.Fab")
		)
		(fp_line
			(start 0.12065 -0.2794)
			(end 0.12065 -0.3048)
			(stroke
				(width 0.1)
				(type default)
			)
			(layer "F.Fab")
		)
		(fp_line
			(start 0.12065 -0.3048)
			(end 0.67945 -0.3048)
			(stroke
				(width 0.1)
				(type default)
			)
			(layer "F.Fab")
		)
		(fp_line
			(start 0.67945 -0.3048)
			(end 0.67945 0.3048)
			(stroke
				(width 0.1)
				(type default)
			)
			(layer "F.Fab")
		)
		(fp_line
			(start -0.67945 -0.305054)
			(end -0.12065 -0.305054)
			(stroke
				(width 0.1)
				(type default)
			)
			(layer "F.Fab")
		)
		(fp_line
			(start -0.12065 -0.305054)
			(end -0.12065 -0.2794)
			(stroke
				(width 0.1)
				(type default)
			)
			(layer "F.Fab")
		)
		(pad "1" smd circle
			(at -0.40005 0 270)
			(size 0 0)
			(layers "F.Cu" "F.Mask" "F.Paste")
			(net "PVDDCR_CPU0_P0_VCC6")
		)
		(pad "2" smd circle
			(at 0.40005 0 270)
			(size 0 0)
			(layers "F.Cu" "F.Mask" "F.Paste")
			(net "GND")
		)
	)
	(footprint ""
		(layer "F.Cu")
		(at 439.072782 -433.49926 90)
		(property "Reference" "R3472"
			(at 0 0 90)
			(layer "F.SilkS")
			(hide yes)
			(effects
				(font
					(size 1.27 1.27)
				)
			)
		)
		(property "Value" ""
			(at 0 0 90)
			(layer "F.Fab")
			(effects
				(font
					(size 1.27 1.27)
				)
			)
		)
		(duplicate_pad_numbers_are_jumpers no)
		(fp_line
			(start 0.7874 -0.4064)
			(end 0.7874 0.4064)
			(stroke
				(width 0.1524)
				(type default)
			)
			(layer "F.SilkS")
		)
		(fp_line
			(start -0.7874 -0.4064)
			(end 0.7874 -0.4064)
			(stroke
				(width 0.1524)
				(type default)
			)
			(layer "F.SilkS")
		)
		(fp_line
			(start 0.7874 0.4064)
			(end -0.7874 0.4064)
			(stroke
				(width 0.1524)
				(type default)
			)
			(layer "F.SilkS")
		)
		(fp_line
			(start -0.7874 0.4064)
			(end -0.7874 -0.4064)
			(stroke
				(width 0.1524)
				(type default)
			)
			(layer "F.SilkS")
		)
		(fp_line
			(start -0.12065 -0.305054)
			(end -0.12065 -0.2794)
			(stroke
				(width 0.1)
				(type default)
			)
			(layer "F.Fab")
		)
		(fp_line
			(start -0.67945 -0.305054)
			(end -0.12065 -0.305054)
			(stroke
				(width 0.1)
				(type default)
			)
			(layer "F.Fab")
		)
		(fp_line
			(start 0.67945 -0.3048)
			(end 0.67945 0.3048)
			(stroke
				(width 0.1)
				(type default)
			)
			(layer "F.Fab")
		)
		(fp_line
			(start 0.12065 -0.3048)
			(end 0.67945 -0.3048)
			(stroke
				(width 0.1)
				(type default)
			)
			(layer "F.Fab")
		)
		(fp_line
			(start 0.12065 -0.2794)
			(end 0.12065 -0.3048)
			(stroke
				(width 0.1)
				(type default)
			)
			(layer "F.Fab")
		)
		(fp_line
			(start -0.12065 -0.2794)
			(end 0.12065 -0.2794)
			(stroke
				(width 0.1)
				(type default)
			)
			(layer "F.Fab")
		)
		(fp_line
			(start 0.120396 0.2794)
			(end -0.12065 0.2794)
			(stroke
				(width 0.1)
				(type default)
			)
			(layer "F.Fab")
		)
		(fp_line
			(start -0.12065 0.2794)
			(end -0.12065 0.3048)
			(stroke
				(width 0.1)
				(type default)
			)
			(layer "F.Fab")
		)
		(fp_line
			(start 0.67945 0.3048)
			(end 0.120396 0.3048)
			(stroke
				(width 0.1)
				(type default)
			)
			(layer "F.Fab")
		)
		(fp_line
			(start 0.120396 0.3048)
			(end 0.120396 0.2794)
			(stroke
				(width 0.1)
				(type default)
			)
			(layer "F.Fab")
		)
		(fp_line
			(start -0.12065 0.3048)
			(end -0.67945 0.3048)
			(stroke
				(width 0.1)
				(type default)
			)
			(layer "F.Fab")
		)
		(fp_line
			(start -0.67945 0.3048)
			(end -0.67945 -0.305054)
			(stroke
				(width 0.1)
				(type default)
			)
			(layer "F.Fab")
		)
		(pad "1" smd circle
			(at -0.40005 0 90)
			(size 0 0)
			(layers "F.Cu" "F.Mask" "F.Paste")
			(net "GND")
		)
		(pad "2" smd circle
			(at 0.40005 0 90)
			(size 0 0)
			(layers "F.Cu" "F.Mask" "F.Paste")
			(net "GPU_WP_HW_CTRL_ISO_N")
		)
	)
	(footprint ""
		(layer "F.Cu")
		(at 297.486324 -119.339614 180)
		(property "Reference" "R3395"
			(at 0 0 180)
			(layer "F.SilkS")
			(hide yes)
			(effects
				(font
					(size 1.27 1.27)
				)
			)
		)
		(property "Value" ""
			(at 0 0 180)
			(layer "F.Fab")
			(effects
				(font
					(size 1.27 1.27)
				)
			)
		)
		(duplicate_pad_numbers_are_jumpers no)
		(fp_line
			(start 0.7874 0.4064)
			(end -0.7874 0.4064)
			(stroke
				(width 0.1524)
				(type default)
			)
			(layer "F.SilkS")
		)
		(fp_line
			(start 0.7874 -0.4064)
			(end 0.7874 0.4064)
			(stroke
				(width 0.1524)
				(type default)
			)
			(layer "F.SilkS")
		)
		(fp_line
			(start -0.7874 0.4064)
			(end -0.7874 -0.4064)
			(stroke
				(width 0.1524)
				(type default)
			)
			(layer "F.SilkS")
		)
		(fp_line
			(start -0.7874 -0.4064)
			(end 0.7874 -0.4064)
			(stroke
				(width 0.1524)
				(type default)
			)
			(layer "F.SilkS")
		)
		(fp_line
			(start 0.67945 0.3048)
			(end 0.120396 0.3048)
			(stroke
				(width 0.1)
				(type default)
			)
			(layer "F.Fab")
		)
		(fp_line
			(start 0.67945 -0.3048)
			(end 0.67945 0.3048)
			(stroke
				(width 0.1)
				(type default)
			)
			(layer "F.Fab")
		)
		(fp_line
			(start 0.12065 -0.2794)
			(end 0.12065 -0.3048)
			(stroke
				(width 0.1)
				(type default)
			)
			(layer "F.Fab")
		)
		(fp_line
			(start 0.12065 -0.3048)
			(end 0.67945 -0.3048)
			(stroke
				(width 0.1)
				(type default)
			)
			(layer "F.Fab")
		)
		(fp_line
			(start 0.120396 0.3048)
			(end 0.120396 0.2794)
			(stroke
				(width 0.1)
				(type default)
			)
			(layer "F.Fab")
		)
		(fp_line
			(start 0.120396 0.2794)
			(end -0.12065 0.2794)
			(stroke
				(width 0.1)
				(type default)
			)
			(layer "F.Fab")
		)
		(fp_line
			(start -0.12065 0.3048)
			(end -0.67945 0.3048)
			(stroke
				(width 0.1)
				(type default)
			)
			(layer "F.Fab")
		)
		(fp_line
			(start -0.12065 0.2794)
			(end -0.12065 0.3048)
			(stroke
				(width 0.1)
				(type default)
			)
			(layer "F.Fab")
		)
		(fp_line
			(start -0.12065 -0.2794)
			(end 0.12065 -0.2794)
			(stroke
				(width 0.1)
				(type default)
			)
			(layer "F.Fab")
		)
		(fp_line
			(start -0.12065 -0.305054)
			(end -0.12065 -0.2794)
			(stroke
				(width 0.1)
				(type default)
			)
			(layer "F.Fab")
		)
		(fp_line
			(start -0.67945 0.3048)
			(end -0.67945 -0.305054)
			(stroke
				(width 0.1)
				(type default)
			)
			(layer "F.Fab")
		)
		(fp_line
			(start -0.67945 -0.305054)
			(end -0.12065 -0.305054)
			(stroke
				(width 0.1)
				(type default)
			)
			(layer "F.Fab")
		)
		(pad "1" smd circle
			(at -0.40005 0 180)
			(size 0 0)
			(layers "F.Cu" "F.Mask" "F.Paste")
			(net "P3V3_AUX")
		)
		(pad "2" smd circle
			(at 0.40005 0 180)
			(size 0 0)
			(layers "F.Cu" "F.Mask" "F.Paste")
			(net "SMB_INA230_3V3AUX_SCL")
		)
	)
	(footprint ""
		(layer "F.Cu")
		(at 257.84048 -51.587146)
		(property "Reference" "PR3944"
			(at 0 0 0)
			(layer "F.SilkS")
			(hide yes)
			(effects
				(font
					(size 1.27 1.27)
				)
			)
		)
		(property "Value" ""
			(at 0 0 0)
			(layer "F.Fab")
			(effects
				(font
					(size 1.27 1.27)
				)
			)
		)
		(duplicate_pad_numbers_are_jumpers no)
		(fp_line
			(start -0.7874 -0.4064)
			(end 0.7874 -0.4064)
			(stroke
				(width 0.1524)
				(type default)
			)
			(layer "F.SilkS")
		)
		(fp_line
			(start -0.7874 0.4064)
			(end -0.7874 -0.4064)
			(stroke
				(width 0.1524)
				(type default)
			)
			(layer "F.SilkS")
		)
		(fp_line
			(start 0.7874 -0.4064)
			(end 0.7874 0.4064)
			(stroke
				(width 0.1524)
				(type default)
			)
			(layer "F.SilkS")
		)
		(fp_line
			(start 0.7874 0.4064)
			(end -0.7874 0.4064)
			(stroke
				(width 0.1524)
				(type default)
			)
			(layer "F.SilkS")
		)
		(fp_line
			(start -0.67945 -0.305054)
			(end -0.12065 -0.305054)
			(stroke
				(width 0.1)
				(type default)
			)
			(layer "F.Fab")
		)
		(fp_line
			(start -0.67945 0.3048)
			(end -0.67945 -0.305054)
			(stroke
				(width 0.1)
				(type default)
			)
			(layer "F.Fab")
		)
		(fp_line
			(start -0.12065 -0.305054)
			(end -0.12065 -0.2794)
			(stroke
				(width 0.1)
				(type default)
			)
			(layer "F.Fab")
		)
		(fp_line
			(start -0.12065 -0.2794)
			(end 0.12065 -0.2794)
			(stroke
				(width 0.1)
				(type default)
			)
			(layer "F.Fab")
		)
		(fp_line
			(start -0.12065 0.2794)
			(end -0.12065 0.3048)
			(stroke
				(width 0.1)
				(type default)
			)
			(layer "F.Fab")
		)
		(fp_line
			(start -0.12065 0.3048)
			(end -0.67945 0.3048)
			(stroke
				(width 0.1)
				(type default)
			)
			(layer "F.Fab")
		)
		(fp_line
			(start 0.120396 0.2794)
			(end -0.12065 0.2794)
			(stroke
				(width 0.1)
				(type default)
			)
			(layer "F.Fab")
		)
		(fp_line
			(start 0.120396 0.3048)
			(end 0.120396 0.2794)
			(stroke
				(width 0.1)
				(type default)
			)
			(layer "F.Fab")
		)
		(fp_line
			(start 0.12065 -0.3048)
			(end 0.67945 -0.3048)
			(stroke
				(width 0.1)
				(type default)
			)
			(layer "F.Fab")
		)
		(fp_line
			(start 0.12065 -0.2794)
			(end 0.12065 -0.3048)
			(stroke
				(width 0.1)
				(type default)
			)
			(layer "F.Fab")
		)
		(fp_line
			(start 0.67945 -0.3048)
			(end 0.67945 0.3048)
			(stroke
				(width 0.1)
				(type default)
			)
			(layer "F.Fab")
		)
		(fp_line
			(start 0.67945 0.3048)
			(end 0.120396 0.3048)
			(stroke
				(width 0.1)
				(type default)
			)
			(layer "F.Fab")
		)
		(pad "1" smd circle
			(at -0.40005 0)
			(size 0 0)
			(layers "F.Cu" "F.Mask" "F.Paste")
			(net "P12V_E1S_ISET_0")
		)
		(pad "2" smd circle
			(at 0.40005 0)
			(size 0 0)
			(layers "F.Cu" "F.Mask" "F.Paste")
			(net "GND")
		)
	)
)
